(kicad_pcb
	(version 20260206)
	(generator "pcbnew")
	(generator_version "10.0")
	(general
		(thickness 1.6)
		(legacy_teardrops no)
	)
	(paper "A4")
	(title_block
		(title "04192023_DAF0TMB3IC0_F0TG_MB_C_brd_V02_OCP.brd")
		(comment 1 "Grand Teton / footprints 5823-5830 of 8354")
	)
	(layers
		(0 "F.Cu" signal "TOP")
		(4 "In1.Cu" signal "GND")
		(6 "In2.Cu" signal "IN1")
		(8 "In3.Cu" signal "GND1")
		(10 "In4.Cu" signal "IN2")
		(12 "In5.Cu" signal "GND2")
		(14 "In6.Cu" signal "IN3")
		(16 "In7.Cu" signal "GND3")
		(18 "In8.Cu" signal "VCC")
		(20 "In9.Cu" signal "VCC1")
		(22 "In10.Cu" signal "GND4")
		(24 "In11.Cu" signal "IN4")
		(26 "In12.Cu" signal "GND5")
		(28 "In13.Cu" signal "IN5")
		(30 "In14.Cu" signal "GND6")
		(32 "In15.Cu" signal "IN6")
		(34 "In16.Cu" signal "GND7")
		(2 "B.Cu" signal "BOTTOM")
		(9 "F.Adhes" user "F.Adhesive")
		(11 "B.Adhes" user "B.Adhesive")
		(13 "F.Paste" user "Package Geometry/Pastemask Top")
		(15 "B.Paste" user "Package Geometry/Pastemask Bottom")
		(5 "F.SilkS" user "Ref Des/Silkscreen Top")
		(7 "B.SilkS" user "Ref Des/Silkscreen Bottom")
		(1 "F.Mask" user "Board Geometry/Soldermask Top")
		(3 "B.Mask" user "Board Geometry/Soldermask Bottom")
		(17 "Dwgs.User" user "User.Drawings")
		(19 "Cmts.User" user "User.Comments")
		(21 "Eco1.User" user "User.Eco1")
		(23 "Eco2.User" user "User.Eco2")
		(25 "Edge.Cuts" user "Board Geometry/Outline")
		(27 "Margin" user)
		(31 "F.CrtYd" user "Package Geometry/Place Bound Top")
		(29 "B.CrtYd" user "Package Geometry/Place Bound Bottom")
		(35 "F.Fab" user "Ref Des/Assembly Top")
		(33 "B.Fab" user "Ref Des/Assembly Bottom")
	)
	(footprint ""
		(layer "B.Cu")
		(at 115.610386 -251.781564)
		(property "Reference" "C2413"
			(at 0 0 0)
			(layer "B.SilkS")
			(hide yes)
			(effects
				(font
					(size 1.27 1.27)
				)
				(justify mirror)
			)
		)
		(property "Value" ""
			(at 0 0 0)
			(layer "B.Fab")
			(effects
				(font
					(size 1.27 1.27)
				)
				(justify mirror)
			)
		)
		(duplicate_pad_numbers_are_jumpers no)
		(fp_line
			(start -0.7874 -0.4064)
			(end -0.7874 0.4064)
			(stroke
				(width 0.1524)
				(type default)
			)
			(layer "B.SilkS")
		)
		(fp_line
			(start -0.7874 0.4064)
			(end 0.7874 0.4064)
			(stroke
				(width 0.1524)
				(type default)
			)
			(layer "B.SilkS")
		)
		(fp_line
			(start 0.7874 -0.4064)
			(end -0.7874 -0.4064)
			(stroke
				(width 0.1524)
				(type default)
			)
			(layer "B.SilkS")
		)
		(fp_line
			(start 0.7874 0.4064)
			(end 0.7874 -0.4064)
			(stroke
				(width 0.1524)
				(type default)
			)
			(layer "B.SilkS")
		)
		(fp_line
			(start -0.67945 -0.3048)
			(end -0.67945 0.3048)
			(stroke
				(width 0.1)
				(type default)
			)
			(layer "B.Fab")
		)
		(fp_line
			(start -0.67945 0.3048)
			(end -0.120396 0.3048)
			(stroke
				(width 0.1)
				(type default)
			)
			(layer "B.Fab")
		)
		(fp_line
			(start -0.12065 -0.3048)
			(end -0.67945 -0.3048)
			(stroke
				(width 0.1)
				(type default)
			)
			(layer "B.Fab")
		)
		(fp_line
			(start -0.12065 -0.2794)
			(end -0.12065 -0.3048)
			(stroke
				(width 0.1)
				(type default)
			)
			(layer "B.Fab")
		)
		(fp_line
			(start -0.120396 0.2794)
			(end 0.12065 0.2794)
			(stroke
				(width 0.1)
				(type default)
			)
			(layer "B.Fab")
		)
		(fp_line
			(start -0.120396 0.3048)
			(end -0.120396 0.2794)
			(stroke
				(width 0.1)
				(type default)
			)
			(layer "B.Fab")
		)
		(fp_line
			(start 0.12065 -0.305054)
			(end 0.12065 -0.2794)
			(stroke
				(width 0.1)
				(type default)
			)
			(layer "B.Fab")
		)
		(fp_line
			(start 0.12065 -0.2794)
			(end -0.12065 -0.2794)
			(stroke
				(width 0.1)
				(type default)
			)
			(layer "B.Fab")
		)
		(fp_line
			(start 0.12065 0.2794)
			(end 0.12065 0.3048)
			(stroke
				(width 0.1)
				(type default)
			)
			(layer "B.Fab")
		)
		(fp_line
			(start 0.12065 0.3048)
			(end 0.67945 0.3048)
			(stroke
				(width 0.1)
				(type default)
			)
			(layer "B.Fab")
		)
		(fp_line
			(start 0.67945 -0.305054)
			(end 0.12065 -0.305054)
			(stroke
				(width 0.1)
				(type default)
			)
			(layer "B.Fab")
		)
		(fp_line
			(start 0.67945 0.3048)
			(end 0.67945 -0.305054)
			(stroke
				(width 0.1)
				(type default)
			)
			(layer "B.Fab")
		)
		(pad "1" smd circle
			(at 0.40005 0 180)
			(size 0 0)
			(layers "B.Cu" "B.Mask" "B.Paste")
			(net "PVDDCR_SOC_P1")
		)
		(pad "2" smd circle
			(at -0.40005 0 180)
			(size 0 0)
			(layers "B.Cu" "B.Mask" "B.Paste")
			(net "GND")
		)
	)
	(footprint ""
		(layer "B.Cu")
		(at 164.338 -424.60037 -90)
		(property "Reference" "R1513"
			(at 0 0 90)
			(layer "B.SilkS")
			(hide yes)
			(effects
				(font
					(size 1.27 1.27)
				)
				(justify mirror)
			)
		)
		(property "Value" ""
			(at 0 0 90)
			(layer "B.Fab")
			(effects
				(font
					(size 1.27 1.27)
				)
				(justify mirror)
			)
		)
		(duplicate_pad_numbers_are_jumpers no)
		(fp_line
			(start -0.32512 0.175006)
			(end 0.32512 0.175006)
			(stroke
				(width 0.1)
				(type default)
			)
			(layer "B.Fab")
		)
		(fp_line
			(start 0.32512 0.175006)
			(end 0.32512 -0.175006)
			(stroke
				(width 0.1)
				(type default)
			)
			(layer "B.Fab")
		)
		(fp_line
			(start -0.32512 -0.175006)
			(end -0.32512 0.175006)
			(stroke
				(width 0.1)
				(type default)
			)
			(layer "B.Fab")
		)
		(fp_line
			(start 0.32512 -0.175006)
			(end -0.32512 -0.175006)
			(stroke
				(width 0.1)
				(type default)
			)
			(layer "B.Fab")
		)
		(pad "1" smd rect
			(at 0.2667 0 90)
			(size 0.3048 0.381)
			(layers "B.Cu" "B.Mask" "B.Paste")
			(net "P1V8_CPU1_RT_1D")
		)
		(pad "2" smd rect
			(at -0.2667 0 270)
			(size 0.3048 0.381)
			(layers "B.Cu" "B.Mask" "B.Paste")
			(net "JTAG_TCK_RT_CPU1_P3")
		)
	)
	(footprint ""
		(layer "B.Cu")
		(at 48.578516 -386.766562 90)
		(property "Reference" "C243"
			(at 0 0 90)
			(layer "B.SilkS")
			(hide yes)
			(effects
				(font
					(size 1.27 1.27)
				)
				(justify mirror)
			)
		)
		(property "Value" ""
			(at 0 0 90)
			(layer "B.Fab")
			(effects
				(font
					(size 1.27 1.27)
				)
				(justify mirror)
			)
		)
		(duplicate_pad_numbers_are_jumpers no)
		(fp_line
			(start 0.299974 -0.150114)
			(end -0.299974 -0.150114)
			(stroke
				(width 0.1)
				(type default)
			)
			(layer "B.Fab")
		)
		(fp_line
			(start -0.299974 -0.150114)
			(end -0.299974 0.150114)
			(stroke
				(width 0.1)
				(type default)
			)
			(layer "B.Fab")
		)
		(fp_line
			(start 0.299974 0.150114)
			(end 0.299974 -0.150114)
			(stroke
				(width 0.1)
				(type default)
			)
			(layer "B.Fab")
		)
		(fp_line
			(start -0.299974 0.150114)
			(end 0.299974 0.150114)
			(stroke
				(width 0.1)
				(type default)
			)
			(layer "B.Fab")
		)
		(pad "1" smd rect
			(at 0.2667 0 270)
			(size 0.3048 0.381)
			(layers "B.Cu" "B.Mask" "B.Paste")
			(net "P0V9_CPU1_RT0_2A")
		)
		(pad "2" smd rect
			(at -0.2667 0 270)
			(size 0.3048 0.381)
			(layers "B.Cu" "B.Mask" "B.Paste")
			(net "GND")
		)
	)
	(footprint ""
		(layer "B.Cu")
		(at 124.373386 -261.04723)
		(property "Reference" "C3913"
			(at 0 0 0)
			(layer "B.SilkS")
			(hide yes)
			(effects
				(font
					(size 1.27 1.27)
				)
				(justify mirror)
			)
		)
		(property "Value" ""
			(at 0 0 0)
			(layer "B.Fab")
			(effects
				(font
					(size 1.27 1.27)
				)
				(justify mirror)
			)
		)
		(duplicate_pad_numbers_are_jumpers no)
		(fp_line
			(start -0.7874 -0.4064)
			(end -0.7874 0.4064)
			(stroke
				(width 0.1524)
				(type default)
			)
			(layer "B.SilkS")
		)
		(fp_line
			(start -0.7874 0.4064)
			(end 0.7874 0.4064)
			(stroke
				(width 0.1524)
				(type default)
			)
			(layer "B.SilkS")
		)
		(fp_line
			(start 0.7874 -0.4064)
			(end -0.7874 -0.4064)
			(stroke
				(width 0.1524)
				(type default)
			)
			(layer "B.SilkS")
		)
		(fp_line
			(start 0.7874 0.4064)
			(end 0.7874 -0.4064)
			(stroke
				(width 0.1524)
				(type default)
			)
			(layer "B.SilkS")
		)
		(fp_line
			(start -0.67945 -0.3048)
			(end -0.67945 0.3048)
			(stroke
				(width 0.1)
				(type default)
			)
			(layer "B.Fab")
		)
		(fp_line
			(start -0.67945 0.3048)
			(end -0.120396 0.3048)
			(stroke
				(width 0.1)
				(type default)
			)
			(layer "B.Fab")
		)
		(fp_line
			(start -0.12065 -0.3048)
			(end -0.67945 -0.3048)
			(stroke
				(width 0.1)
				(type default)
			)
			(layer "B.Fab")
		)
		(fp_line
			(start -0.12065 -0.2794)
			(end -0.12065 -0.3048)
			(stroke
				(width 0.1)
				(type default)
			)
			(layer "B.Fab")
		)
		(fp_line
			(start -0.120396 0.2794)
			(end 0.12065 0.2794)
			(stroke
				(width 0.1)
				(type default)
			)
			(layer "B.Fab")
		)
		(fp_line
			(start -0.120396 0.3048)
			(end -0.120396 0.2794)
			(stroke
				(width 0.1)
				(type default)
			)
			(layer "B.Fab")
		)
		(fp_line
			(start 0.12065 -0.305054)
			(end 0.12065 -0.2794)
			(stroke
				(width 0.1)
				(type default)
			)
			(layer "B.Fab")
		)
		(fp_line
			(start 0.12065 -0.2794)
			(end -0.12065 -0.2794)
			(stroke
				(width 0.1)
				(type default)
			)
			(layer "B.Fab")
		)
		(fp_line
			(start 0.12065 0.2794)
			(end 0.12065 0.3048)
			(stroke
				(width 0.1)
				(type default)
			)
			(layer "B.Fab")
		)
		(fp_line
			(start 0.12065 0.3048)
			(end 0.67945 0.3048)
			(stroke
				(width 0.1)
				(type default)
			)
			(layer "B.Fab")
		)
		(fp_line
			(start 0.67945 -0.305054)
			(end 0.12065 -0.305054)
			(stroke
				(width 0.1)
				(type default)
			)
			(layer "B.Fab")
		)
		(fp_line
			(start 0.67945 0.3048)
			(end 0.67945 -0.305054)
			(stroke
				(width 0.1)
				(type default)
			)
			(layer "B.Fab")
		)
		(pad "1" smd circle
			(at 0.40005 0 180)
			(size 0 0)
			(layers "B.Cu" "B.Mask" "B.Paste")
			(net "PVDDCR_SOC_P1")
		)
		(pad "2" smd circle
			(at -0.40005 0 180)
			(size 0 0)
			(layers "B.Cu" "B.Mask" "B.Paste")
			(net "GND")
		)
	)
	(footprint ""
		(layer "B.Cu")
		(at 184.719468 -425.467526 -90)
		(property "Reference" "R8112"
			(at 0 0 90)
			(layer "B.SilkS")
			(hide yes)
			(effects
				(font
					(size 1.27 1.27)
				)
				(justify mirror)
			)
		)
		(property "Value" ""
			(at 0 0 90)
			(layer "B.Fab")
			(effects
				(font
					(size 1.27 1.27)
				)
				(justify mirror)
			)
		)
		(duplicate_pad_numbers_are_jumpers no)
		(fp_line
			(start -0.7874 0.4064)
			(end 0.7874 0.4064)
			(stroke
				(width 0.1524)
				(type default)
			)
			(layer "B.SilkS")
		)
		(fp_line
			(start 0.7874 0.4064)
			(end 0.7874 -0.4064)
			(stroke
				(width 0.1524)
				(type default)
			)
			(layer "B.SilkS")
		)
		(fp_line
			(start -0.7874 -0.4064)
			(end -0.7874 0.4064)
			(stroke
				(width 0.1524)
				(type default)
			)
			(layer "B.SilkS")
		)
		(fp_line
			(start 0.7874 -0.4064)
			(end -0.7874 -0.4064)
			(stroke
				(width 0.1524)
				(type default)
			)
			(layer "B.SilkS")
		)
		(fp_line
			(start -0.67945 0.3048)
			(end -0.120396 0.3048)
			(stroke
				(width 0.1)
				(type default)
			)
			(layer "B.Fab")
		)
		(fp_line
			(start -0.120396 0.3048)
			(end -0.120396 0.2794)
			(stroke
				(width 0.1)
				(type default)
			)
			(layer "B.Fab")
		)
		(fp_line
			(start 0.12065 0.3048)
			(end 0.67945 0.3048)
			(stroke
				(width 0.1)
				(type default)
			)
			(layer "B.Fab")
		)
		(fp_line
			(start 0.67945 0.3048)
			(end 0.67945 -0.305054)
			(stroke
				(width 0.1)
				(type default)
			)
			(layer "B.Fab")
		)
		(fp_line
			(start -0.120396 0.2794)
			(end 0.12065 0.2794)
			(stroke
				(width 0.1)
				(type default)
			)
			(layer "B.Fab")
		)
		(fp_line
			(start 0.12065 0.2794)
			(end 0.12065 0.3048)
			(stroke
				(width 0.1)
				(type default)
			)
			(layer "B.Fab")
		)
		(fp_line
			(start -0.12065 -0.2794)
			(end -0.12065 -0.3048)
			(stroke
				(width 0.1)
				(type default)
			)
			(layer "B.Fab")
		)
		(fp_line
			(start 0.12065 -0.2794)
			(end -0.12065 -0.2794)
			(stroke
				(width 0.1)
				(type default)
			)
			(layer "B.Fab")
		)
		(fp_line
			(start -0.67945 -0.3048)
			(end -0.67945 0.3048)
			(stroke
				(width 0.1)
				(type default)
			)
			(layer "B.Fab")
		)
		(fp_line
			(start -0.12065 -0.3048)
			(end -0.67945 -0.3048)
			(stroke
				(width 0.1)
				(type default)
			)
			(layer "B.Fab")
		)
		(fp_line
			(start 0.12065 -0.305054)
			(end 0.12065 -0.2794)
			(stroke
				(width 0.1)
				(type default)
			)
			(layer "B.Fab")
		)
		(fp_line
			(start 0.67945 -0.305054)
			(end 0.12065 -0.305054)
			(stroke
				(width 0.1)
				(type default)
			)
			(layer "B.Fab")
		)
		(pad "1" smd circle
			(at 0.40005 0 90)
			(size 0 0)
			(layers "B.Cu" "B.Mask" "B.Paste")
			(net "HSC_OC_VOL")
		)
		(pad "2" smd circle
			(at -0.40005 0 90)
			(size 0 0)
			(layers "B.Cu" "B.Mask" "B.Paste")
			(net "HSC_D_OC_R2")
		)
	)
	(footprint ""
		(layer "B.Cu")
		(at 40.045386 -190.948564 180)
		(property "Reference" "R305"
			(at 0 0 0)
			(layer "B.SilkS")
			(hide yes)
			(effects
				(font
					(size 1.27 1.27)
				)
				(justify mirror)
			)
		)
		(property "Value" ""
			(at 0 0 0)
			(layer "B.Fab")
			(effects
				(font
					(size 1.27 1.27)
				)
				(justify mirror)
			)
		)
		(duplicate_pad_numbers_are_jumpers no)
		(fp_line
			(start 0.7874 0.4064)
			(end 0.7874 -0.4064)
			(stroke
				(width 0.1524)
				(type default)
			)
			(layer "B.SilkS")
		)
		(fp_line
			(start 0.7874 -0.4064)
			(end -0.7874 -0.4064)
			(stroke
				(width 0.1524)
				(type default)
			)
			(layer "B.SilkS")
		)
		(fp_line
			(start -0.7874 0.4064)
			(end 0.7874 0.4064)
			(stroke
				(width 0.1524)
				(type default)
			)
			(layer "B.SilkS")
		)
		(fp_line
			(start -0.7874 -0.4064)
			(end -0.7874 0.4064)
			(stroke
				(width 0.1524)
				(type default)
			)
			(layer "B.SilkS")
		)
		(fp_line
			(start 0.67945 0.3048)
			(end 0.67945 -0.305054)
			(stroke
				(width 0.1)
				(type default)
			)
			(layer "B.Fab")
		)
		(fp_line
			(start 0.67945 -0.305054)
			(end 0.12065 -0.305054)
			(stroke
				(width 0.1)
				(type default)
			)
			(layer "B.Fab")
		)
		(fp_line
			(start 0.12065 0.3048)
			(end 0.67945 0.3048)
			(stroke
				(width 0.1)
				(type default)
			)
			(layer "B.Fab")
		)
		(fp_line
			(start 0.12065 0.2794)
			(end 0.12065 0.3048)
			(stroke
				(width 0.1)
				(type default)
			)
			(layer "B.Fab")
		)
		(fp_line
			(start 0.12065 -0.2794)
			(end -0.12065 -0.2794)
			(stroke
				(width 0.1)
				(type default)
			)
			(layer "B.Fab")
		)
		(fp_line
			(start 0.12065 -0.305054)
			(end 0.12065 -0.2794)
			(stroke
				(width 0.1)
				(type default)
			)
			(layer "B.Fab")
		)
		(fp_line
			(start -0.120396 0.3048)
			(end -0.120396 0.2794)
			(stroke
				(width 0.1)
				(type default)
			)
			(layer "B.Fab")
		)
		(fp_line
			(start -0.120396 0.2794)
			(end 0.12065 0.2794)
			(stroke
				(width 0.1)
				(type default)
			)
			(layer "B.Fab")
		)
		(fp_line
			(start -0.12065 -0.2794)
			(end -0.12065 -0.3048)
			(stroke
				(width 0.1)
				(type default)
			)
			(layer "B.Fab")
		)
		(fp_line
			(start -0.12065 -0.3048)
			(end -0.67945 -0.3048)
			(stroke
				(width 0.1)
				(type default)
			)
			(layer "B.Fab")
		)
		(fp_line
			(start -0.67945 0.3048)
			(end -0.120396 0.3048)
			(stroke
				(width 0.1)
				(type default)
			)
			(layer "B.Fab")
		)
		(fp_line
			(start -0.67945 -0.3048)
			(end -0.67945 0.3048)
			(stroke
				(width 0.1)
				(type default)
			)
			(layer "B.Fab")
		)
		(pad "1" smd circle
			(at 0.40005 0)
			(size 0 0)
			(layers "B.Cu" "B.Mask" "B.Paste")
			(net "PWRGD_CHC_CPU1_DIMM")
		)
		(pad "2" smd circle
			(at -0.40005 0)
			(size 0 0)
			(layers "B.Cu" "B.Mask" "B.Paste")
			(net "PWRGD_CHAF_CPU1")
		)
	)
	(footprint ""
		(layer "B.Cu")
		(at 184.05983 -13.60043 -90)
		(property "Reference" "R6006"
			(at 0 0 90)
			(layer "B.SilkS")
			(hide yes)
			(effects
				(font
					(size 1.27 1.27)
				)
				(justify mirror)
			)
		)
		(property "Value" ""
			(at 0 0 90)
			(layer "B.Fab")
			(effects
				(font
					(size 1.27 1.27)
				)
				(justify mirror)
			)
		)
		(duplicate_pad_numbers_are_jumpers no)
		(fp_line
			(start -0.7874 0.4064)
			(end 0.7874 0.4064)
			(stroke
				(width 0.1524)
				(type default)
			)
			(layer "B.SilkS")
		)
		(fp_line
			(start 0.7874 0.4064)
			(end 0.7874 -0.4064)
			(stroke
				(width 0.1524)
				(type default)
			)
			(layer "B.SilkS")
		)
		(fp_line
			(start -0.7874 -0.4064)
			(end -0.7874 0.4064)
			(stroke
				(width 0.1524)
				(type default)
			)
			(layer "B.SilkS")
		)
		(fp_line
			(start 0.7874 -0.4064)
			(end -0.7874 -0.4064)
			(stroke
				(width 0.1524)
				(type default)
			)
			(layer "B.SilkS")
		)
		(fp_line
			(start -0.67945 0.3048)
			(end -0.120396 0.3048)
			(stroke
				(width 0.1)
				(type default)
			)
			(layer "B.Fab")
		)
		(fp_line
			(start -0.120396 0.3048)
			(end -0.120396 0.2794)
			(stroke
				(width 0.1)
				(type default)
			)
			(layer "B.Fab")
		)
		(fp_line
			(start 0.12065 0.3048)
			(end 0.67945 0.3048)
			(stroke
				(width 0.1)
				(type default)
			)
			(layer "B.Fab")
		)
		(fp_line
			(start 0.67945 0.3048)
			(end 0.67945 -0.305054)
			(stroke
				(width 0.1)
				(type default)
			)
			(layer "B.Fab")
		)
		(fp_line
			(start -0.120396 0.2794)
			(end 0.12065 0.2794)
			(stroke
				(width 0.1)
				(type default)
			)
			(layer "B.Fab")
		)
		(fp_line
			(start 0.12065 0.2794)
			(end 0.12065 0.3048)
			(stroke
				(width 0.1)
				(type default)
			)
			(layer "B.Fab")
		)
		(fp_line
			(start -0.12065 -0.2794)
			(end -0.12065 -0.3048)
			(stroke
				(width 0.1)
				(type default)
			)
			(layer "B.Fab")
		)
		(fp_line
			(start 0.12065 -0.2794)
			(end -0.12065 -0.2794)
			(stroke
				(width 0.1)
				(type default)
			)
			(layer "B.Fab")
		)
		(fp_line
			(start -0.67945 -0.3048)
			(end -0.67945 0.3048)
			(stroke
				(width 0.1)
				(type default)
			)
			(layer "B.Fab")
		)
		(fp_line
			(start -0.12065 -0.3048)
			(end -0.67945 -0.3048)
			(stroke
				(width 0.1)
				(type default)
			)
			(layer "B.Fab")
		)
		(fp_line
			(start 0.12065 -0.305054)
			(end 0.12065 -0.2794)
			(stroke
				(width 0.1)
				(type default)
			)
			(layer "B.Fab")
		)
		(fp_line
			(start 0.67945 -0.305054)
			(end 0.12065 -0.305054)
			(stroke
				(width 0.1)
				(type default)
			)
			(layer "B.Fab")
		)
		(pad "1" smd circle
			(at 0.40005 0 90)
			(size 0 0)
			(layers "B.Cu" "B.Mask" "B.Paste")
			(net "I3C_SCM_3_SCL")
		)
		(pad "2" smd circle
			(at -0.40005 0 90)
			(size 0 0)
			(layers "B.Cu" "B.Mask" "B.Paste")
			(net "I3C_SCM_3_R_SCL")
		)
	)
	(footprint ""
		(layer "B.Cu")
		(at 138.757406 -408.517344 90)
		(property "Reference" "C6739"
			(at 0 0 90)
			(layer "B.SilkS")
			(hide yes)
			(effects
				(font
					(size 1.27 1.27)
				)
				(justify mirror)
			)
		)
		(property "Value" ""
			(at 0 0 90)
			(layer "B.Fab")
			(effects
				(font
					(size 1.27 1.27)
				)
				(justify mirror)
			)
		)
		(duplicate_pad_numbers_are_jumpers no)
		(fp_line
			(start 0.299974 -0.150114)
			(end -0.299974 -0.150114)
			(stroke
				(width 0.1)
				(type default)
			)
			(layer "B.Fab")
		)
		(fp_line
			(start -0.299974 -0.150114)
			(end -0.299974 0.150114)
			(stroke
				(width 0.1)
				(type default)
			)
			(layer "B.Fab")
		)
		(fp_line
			(start 0.299974 0.150114)
			(end 0.299974 -0.150114)
			(stroke
				(width 0.1)
				(type default)
			)
			(layer "B.Fab")
		)
		(fp_line
			(start -0.299974 0.150114)
			(end 0.299974 0.150114)
			(stroke
				(width 0.1)
				(type default)
			)
			(layer "B.Fab")
		)
		(pad "1" smd rect
			(at 0.2667 0 270)
			(size 0.3048 0.381)
			(layers "B.Cu" "B.Mask" "B.Paste")
			(net "P5E_CPU1_P3_TX_BUF_C_DP<7>")
		)
		(pad "2" smd rect
			(at -0.2667 0 270)
			(size 0.3048 0.381)
			(layers "B.Cu" "B.Mask" "B.Paste")
			(net "P5E_CPU1_P3_TX_BUF_DP<7>")
		)
	)
)
